G04 ================== begin FILE IDENTIFICATION RECORD ==================*
G04 Layout Name:  12523-1.brd*
G04 Film Name:    TMASK*
G04 File Format:  Gerber RS274X*
G04 File Origin:  Cadence Allegro 16.2-s031*
G04 Origin Date:  Fri Oct 19 14:59:08 2012*
G04 *
G04 Layer:  VIA CLASS/SOLDERMASK_TOP*
G04 Layer:  PIN/SOLDERMASK_TOP*
G04 Layer:  PACKAGE GEOMETRY/SOLDERMASK_TOP*
G04 Layer:  DRAWING FORMAT/LAYER_PCB_STORY*
G04 Layer:  DRAWING FORMAT/LAYER_SOLDER_T*
G04 Layer:  BOARD GEOMETRY/SOLDERMASK_TOP*
G04 *
G04 Offset:    (0.00 0.00)*
G04 Mirror:    No*
G04 Mode:      Positive*
G04 Rotation:  0*
G04 FullContactRelief:  No*
G04 UndefLineWidth:     6.00*
G04 ================== end FILE IDENTIFICATION RECORD ====================*
%FSLAX35Y35*MOIN*%
%IR0*IPPOS*OFA0.00000B0.00000*MIA0B0*SFA1.00000B1.00000*%
%AMMACRO24*
4,1,40,.017,-.013,
.017,.013,
.016939,.013695,
.016759,.014368,
.016464,.015,
.016064,.015571,
.015571,.016064,
.015,.016464,
.014368,.016759,
.013695,.016939,
.013,.017,
-.013,.017,
-.013695,.016939,
-.014368,.016759,
-.015,.016464,
-.015571,.016064,
-.016064,.015571,
-.016464,.015,
-.016759,.014368,
-.016939,.013695,
-.017,.013,
-.017,-.013,
-.016939,-.013695,
-.016759,-.014368,
-.016464,-.015,
-.016064,-.015571,
-.015571,-.016064,
-.015,-.016464,
-.014368,-.016759,
-.013695,-.016939,
-.013,-.017,
.013,-.017,
.013695,-.016939,
.014368,-.016759,
.015,-.016464,
.015571,-.016064,
.016064,-.015571,
.016464,-.015,
.016759,-.014368,
.016939,-.013695,
.017,-.013,
0.0*
%
%ADD24MACRO24*%
%ADD35R,.11X.055*%
%ADD42R,.074X.122*%
%AMMACRO11*
4,1,21,.062,.1775,
.092823,.174803,
.122709,.166795,
.15075,.15372,
.176095,.135973,
.197973,.114095,
.21572,.08875,
.228795,.060709,
.236803,.030823,
.2395,0.0,
.236803,-.030823,
.228795,-.060709,
.21572,-.08875,
.197973,-.114095,
.176095,-.135973,
.15075,-.15372,
.122709,-.166795,
.092823,-.174803,
.062,-.1775,
-.2395,-.1775,
-.2395,.1775,
.062,.1775,
0.0*
%
%ADD11MACRO11*%
%ADD33C,.032*%
%ADD39C,.034*%
%ADD40C,.053*%
%ADD16R,.197X.032*%
%ADD29C,.028*%
%ADD37C,.057*%
%ADD10C,.086*%
%AMMACRO31*
4,1,40,.007,.011,
-.007,.011,
-.007695,.010939,
-.008368,.010759,
-.009,.010464,
-.009571,.010064,
-.010064,.009571,
-.010464,.009,
-.010759,.008368,
-.010939,.007695,
-.011,.007,
-.011,-.007,
-.010939,-.007695,
-.010759,-.008368,
-.010464,-.009,
-.010064,-.009571,
-.009571,-.010064,
-.009,-.010464,
-.008368,-.010759,
-.007695,-.010939,
-.007,-.011,
.007,-.011,
.007695,-.010939,
.008368,-.010759,
.009,-.010464,
.009571,-.010064,
.010064,-.009571,
.010464,-.009,
.010759,-.008368,
.010939,-.007695,
.011,-.007,
.011,.007,
.010939,.007695,
.010759,.008368,
.010464,.009,
.010064,.009571,
.009571,.010064,
.009,.010464,
.008368,.010759,
.007695,.010939,
.007,.011,
0.0*
%
%ADD31MACRO31*%
%AMMACRO22*
4,1,40,.011,-.007,
.011,.007,
.010939,.007695,
.010759,.008368,
.010464,.009,
.010064,.009571,
.009571,.010064,
.009,.010464,
.008368,.010759,
.007695,.010939,
.007,.011,
-.007,.011,
-.007695,.010939,
-.008368,.010759,
-.009,.010464,
-.009571,.010064,
-.010064,.009571,
-.010464,.009,
-.010759,.008368,
-.010939,.007695,
-.011,.007,
-.011,-.007,
-.010939,-.007695,
-.010759,-.008368,
-.010464,-.009,
-.010064,-.009571,
-.009571,-.010064,
-.009,-.010464,
-.008368,-.010759,
-.007695,-.010939,
-.007,-.011,
.007,-.011,
.007695,-.010939,
.008368,-.010759,
.009,-.010464,
.009571,-.010064,
.010064,-.009571,
.010464,-.009,
.010759,-.008368,
.010939,-.007695,
.011,-.007,
0.0*
%
%ADD22MACRO22*%
%AMMACRO25*
4,1,40,-.017,.013,
-.017,-.013,
-.016939,-.013695,
-.016759,-.014368,
-.016464,-.015,
-.016064,-.015571,
-.015571,-.016064,
-.015,-.016464,
-.014368,-.016759,
-.013695,-.016939,
-.013,-.017,
.013,-.017,
.013695,-.016939,
.014368,-.016759,
.015,-.016464,
.015571,-.016064,
.016064,-.015571,
.016464,-.015,
.016759,-.014368,
.016939,-.013695,
.017,-.013,
.017,.013,
.016939,.013695,
.016759,.014368,
.016464,.015,
.016064,.015571,
.015571,.016064,
.015,.016464,
.014368,.016759,
.013695,.016939,
.013,.017,
-.013,.017,
-.013695,.016939,
-.014368,.016759,
-.015,.016464,
-.015571,.016064,
-.016064,.015571,
-.016464,.015,
-.016759,.014368,
-.016939,.013695,
-.017,.013,
0.0*
%
%ADD25MACRO25*%
%AMMACRO32*
4,1,40,.007,.011,
-.007,.011,
-.007695,.010939,
-.008368,.010759,
-.009,.010464,
-.009571,.010064,
-.010064,.009571,
-.010464,.009,
-.010759,.008368,
-.010939,.007695,
-.011,.007,
-.011,-.007,
-.010939,-.007695,
-.010759,-.008368,
-.010464,-.009,
-.010064,-.009571,
-.009571,-.010064,
-.009,-.010464,
-.008368,-.010759,
-.007695,-.010939,
-.007,-.011,
.007,-.011,
.007695,-.010939,
.008368,-.010759,
.009,-.010464,
.009571,-.010064,
.010064,-.009571,
.010464,-.009,
.010759,-.008368,
.010939,-.007695,
.011,-.007,
.011,.007,
.010939,.007695,
.010759,.008368,
.010464,.009,
.010064,.009571,
.009571,.010064,
.009,.010464,
.008368,.010759,
.007695,.010939,
.007,.011,
0.0*
%
%ADD32MACRO32*%
%AMMACRO23*
4,1,40,.011,-.007,
.011,.007,
.010939,.007695,
.010759,.008368,
.010464,.009,
.010064,.009571,
.009571,.010064,
.009,.010464,
.008368,.010759,
.007695,.010939,
.007,.011,
-.007,.011,
-.007695,.010939,
-.008368,.010759,
-.009,.010464,
-.009571,.010064,
-.010064,.009571,
-.010464,.009,
-.010759,.008368,
-.010939,.007695,
-.011,.007,
-.011,-.007,
-.010939,-.007695,
-.010759,-.008368,
-.010464,-.009,
-.010064,-.009571,
-.009571,-.010064,
-.009,-.010464,
-.008368,-.010759,
-.007695,-.010939,
-.007,-.011,
.007,-.011,
.007695,-.010939,
.008368,-.010759,
.009,-.010464,
.009571,-.010064,
.010064,-.009571,
.010464,-.009,
.010759,-.008368,
.010939,-.007695,
.011,-.007,
0.0*
%
%ADD23MACRO23*%
%AMMACRO26*
4,1,40,-.017,.013,
-.017,-.013,
-.016939,-.013695,
-.016759,-.014368,
-.016464,-.015,
-.016064,-.015571,
-.015571,-.016064,
-.015,-.016464,
-.014368,-.016759,
-.013695,-.016939,
-.013,-.017,
.013,-.017,
.013695,-.016939,
.014368,-.016759,
.015,-.016464,
.015571,-.016064,
.016064,-.015571,
.016464,-.015,
.016759,-.014368,
.016939,-.013695,
.017,-.013,
.017,.013,
.016939,.013695,
.016759,.014368,
.016464,.015,
.016064,.015571,
.015571,.016064,
.015,.016464,
.014368,.016759,
.013695,.016939,
.013,.017,
-.013,.017,
-.013695,.016939,
-.014368,.016759,
-.015,.016464,
-.015571,.016064,
-.016064,.015571,
-.016464,.015,
-.016759,.014368,
-.016939,.013695,
-.017,.013,
0.0*
%
%ADD26MACRO26*%
%ADD17R,.016X.06*%
%ADD14R,.055X.045*%
%ADD15R,.248X.165*%
%ADD13R,.248X.372*%
%ADD41C,.158*%
%ADD34O,.827X.355*%
%ADD12R,.16X.16*%
%AMMACRO38*
4,1,40,.007,.0225,
.008389,.022378,
.009736,.022018,
.011,.021428,
.012142,.020628,
.013128,.019642,
.013928,.0185,
.014518,.017236,
.014878,.015889,
.015,.0145,
.015,-.0145,
.014878,-.015889,
.014518,-.017236,
.013928,-.0185,
.013128,-.019642,
.012142,-.020628,
.011,-.021428,
.009736,-.022018,
.008389,-.022378,
.007,-.0225,
-.007,-.0225,
-.008389,-.022378,
-.009736,-.022018,
-.011,-.021428,
-.012142,-.020628,
-.013128,-.019642,
-.013928,-.0185,
-.014518,-.017236,
-.014878,-.015889,
-.015,-.0145,
-.015,.0145,
-.014878,.015889,
-.014518,.017236,
-.013928,.0185,
-.013128,.019642,
-.012142,.020628,
-.011,.021428,
-.009736,.022018,
-.008389,.022378,
-.007,.0225,
.007,.0225,
0.0*
%
%ADD38MACRO38*%
%ADD36R,.095X.09*%
%AMMACRO30*
4,1,40,-.008,-.012,
.008,-.012,
.008695,-.011939,
.009368,-.011759,
.01,-.011464,
.010571,-.011064,
.011064,-.010571,
.011464,-.01,
.011759,-.009368,
.011939,-.008695,
.012,-.008,
.012,.008,
.011939,.008695,
.011759,.009368,
.011464,.01,
.011064,.010571,
.010571,.011064,
.01,.011464,
.009368,.011759,
.008695,.011939,
.008,.012,
-.008,.012,
-.008695,.011939,
-.009368,.011759,
-.01,.011464,
-.010571,.011064,
-.011064,.010571,
-.011464,.01,
-.011759,.009368,
-.011939,.008695,
-.012,.008,
-.012,-.008,
-.011939,-.008695,
-.011759,-.009368,
-.011464,-.01,
-.011064,-.010571,
-.010571,-.011064,
-.01,-.011464,
-.009368,-.011759,
-.008695,-.011939,
-.008,-.012,
0.0*
%
%ADD30MACRO30*%
%AMMACRO18*
4,1,40,-.007,-.011,
.007,-.011,
.007695,-.010939,
.008368,-.010759,
.009,-.010464,
.009571,-.010064,
.010064,-.009571,
.010464,-.009,
.010759,-.008368,
.010939,-.007695,
.011,-.007,
.011,.007,
.010939,.007695,
.010759,.008368,
.010464,.009,
.010064,.009571,
.009571,.010064,
.009,.010464,
.008368,.010759,
.007695,.010939,
.007,.011,
-.007,.011,
-.007695,.010939,
-.008368,.010759,
-.009,.010464,
-.009571,.010064,
-.010064,.009571,
-.010464,.009,
-.010759,.008368,
-.010939,.007695,
-.011,.007,
-.011,-.007,
-.010939,-.007695,
-.010759,-.008368,
-.010464,-.009,
-.010064,-.009571,
-.009571,-.010064,
-.009,-.010464,
-.008368,-.010759,
-.007695,-.010939,
-.007,-.011,
0.0*
%
%ADD18MACRO18*%
%AMMACRO20*
4,1,40,-.011,.007,
-.011,-.007,
-.010939,-.007695,
-.010759,-.008368,
-.010464,-.009,
-.010064,-.009571,
-.009571,-.010064,
-.009,-.010464,
-.008368,-.010759,
-.007695,-.010939,
-.007,-.011,
.007,-.011,
.007695,-.010939,
.008368,-.010759,
.009,-.010464,
.009571,-.010064,
.010064,-.009571,
.010464,-.009,
.010759,-.008368,
.010939,-.007695,
.011,-.007,
.011,.007,
.010939,.007695,
.010759,.008368,
.010464,.009,
.010064,.009571,
.009571,.010064,
.009,.010464,
.008368,.010759,
.007695,.010939,
.007,.011,
-.007,.011,
-.007695,.010939,
-.008368,.010759,
-.009,.010464,
-.009571,.010064,
-.010064,.009571,
-.010464,.009,
-.010759,.008368,
-.010939,.007695,
-.011,.007,
0.0*
%
%ADD20MACRO20*%
%AMMACRO27*
4,1,40,.017,-.013,
.017,.013,
.016939,.013695,
.016759,.014368,
.016464,.015,
.016064,.015571,
.015571,.016064,
.015,.016464,
.014368,.016759,
.013695,.016939,
.013,.017,
-.013,.017,
-.013695,.016939,
-.014368,.016759,
-.015,.016464,
-.015571,.016064,
-.016064,.015571,
-.016464,.015,
-.016759,.014368,
-.016939,.013695,
-.017,.013,
-.017,-.013,
-.016939,-.013695,
-.016759,-.014368,
-.016464,-.015,
-.016064,-.015571,
-.015571,-.016064,
-.015,-.016464,
-.014368,-.016759,
-.013695,-.016939,
-.013,-.017,
.013,-.017,
.013695,-.016939,
.014368,-.016759,
.015,-.016464,
.015571,-.016064,
.016064,-.015571,
.016464,-.015,
.016759,-.014368,
.016939,-.013695,
.017,-.013,
0.0*
%
%ADD27MACRO27*%
%AMMACRO28*
4,1,40,-.008,-.012,
.008,-.012,
.008695,-.011939,
.009368,-.011759,
.01,-.011464,
.010571,-.011064,
.011064,-.010571,
.011464,-.01,
.011759,-.009368,
.011939,-.008695,
.012,-.008,
.012,.008,
.011939,.008695,
.011759,.009368,
.011464,.01,
.011064,.010571,
.010571,.011064,
.01,.011464,
.009368,.011759,
.008695,.011939,
.008,.012,
-.008,.012,
-.008695,.011939,
-.009368,.011759,
-.01,.011464,
-.010571,.011064,
-.011064,.010571,
-.011464,.01,
-.011759,.009368,
-.011939,.008695,
-.012,.008,
-.012,-.008,
-.011939,-.008695,
-.011759,-.009368,
-.011464,-.01,
-.011064,-.010571,
-.010571,-.011064,
-.01,-.011464,
-.009368,-.011759,
-.008695,-.011939,
-.008,-.012,
0.0*
%
%ADD28MACRO28*%
%AMMACRO19*
4,1,40,-.007,-.011,
.007,-.011,
.007695,-.010939,
.008368,-.010759,
.009,-.010464,
.009571,-.010064,
.010064,-.009571,
.010464,-.009,
.010759,-.008368,
.010939,-.007695,
.011,-.007,
.011,.007,
.010939,.007695,
.010759,.008368,
.010464,.009,
.010064,.009571,
.009571,.010064,
.009,.010464,
.008368,.010759,
.007695,.010939,
.007,.011,
-.007,.011,
-.007695,.010939,
-.008368,.010759,
-.009,.010464,
-.009571,.010064,
-.010064,.009571,
-.010464,.009,
-.010759,.008368,
-.010939,.007695,
-.011,.007,
-.011,-.007,
-.010939,-.007695,
-.010759,-.008368,
-.010464,-.009,
-.010064,-.009571,
-.009571,-.010064,
-.009,-.010464,
-.008368,-.010759,
-.007695,-.010939,
-.007,-.011,
0.0*
%
%ADD19MACRO19*%
%AMMACRO21*
4,1,40,-.011,.007,
-.011,-.007,
-.010939,-.007695,
-.010759,-.008368,
-.010464,-.009,
-.010064,-.009571,
-.009571,-.010064,
-.009,-.010464,
-.008368,-.010759,
-.007695,-.010939,
-.007,-.011,
.007,-.011,
.007695,-.010939,
.008368,-.010759,
.009,-.010464,
.009571,-.010064,
.010064,-.009571,
.010464,-.009,
.010759,-.008368,
.010939,-.007695,
.011,-.007,
.011,.007,
.010939,.007695,
.010759,.008368,
.010464,.009,
.010064,.009571,
.009571,.010064,
.009,.010464,
.008368,.010759,
.007695,.010939,
.007,.011,
-.007,.011,
-.007695,.010939,
-.008368,.010759,
-.009,.010464,
-.009571,.010064,
-.010064,.009571,
-.010464,.009,
-.010759,.008368,
-.010939,.007695,
-.011,.007,
0.0*
%
%ADD21MACRO21*%
%ADD43C,.02*%
%ADD44C,.006*%
G75*
%LPD*%
G75*
G36*
G01X-43611Y110602D02*
X-12605D01*
Y291274D01*
X-17705D01*
Y366242D01*
X-43611D01*
Y110602D01*
G37*
G54D10*
X-23621Y15748D03*
Y937008D03*
X1312285Y15747D03*
G54D20*
X43072Y365847D03*
X43159Y373885D03*
X55352Y387374D03*
X60052Y387292D03*
X51094Y387325D03*
X538000Y293300D03*
X583000Y76800D03*
G54D11*
X23957Y61023D03*
Y415354D03*
G54D21*
X43072Y369247D03*
X43159Y377285D03*
X55352Y390774D03*
X60052Y390692D03*
X51094Y390725D03*
X538000Y296700D03*
X583000Y80200D03*
G54D30*
X41309Y391063D03*
G54D12*
X-23622Y62794D03*
Y916269D03*
X1297695Y58466D03*
G54D13*
X-25005Y173422D03*
Y133422D03*
Y213422D03*
Y253422D03*
G54D22*
X57398Y355860D03*
X48325Y355850D03*
X52705Y355795D03*
G54D31*
X66091Y365163D03*
X577707Y66918D03*
X522800Y322000D03*
X530136Y334902D03*
G54D40*
X596102Y66929D03*
X602008Y74803D03*
X596102Y82677D03*
G54D41*
X600709Y136909D03*
Y311909D03*
G54D14*
X197Y189819D03*
Y197419D03*
X9297Y189819D03*
Y197419D03*
X472898Y182636D03*
Y190236D03*
X550498Y322336D03*
Y329936D03*
G54D23*
X57398Y352460D03*
X48325Y352450D03*
X52705Y352395D03*
G54D32*
X69491Y365163D03*
X526200Y322000D03*
X533536Y334902D03*
X581107Y66918D03*
G54D15*
X-25005Y283072D03*
G54D33*
X67408Y391259D03*
G54D42*
X618566Y343800D03*
X607104D03*
Y387500D03*
X618566D03*
G54D24*
X45807Y388068D03*
X38128Y374332D03*
X542500Y269171D03*
X634488Y72003D03*
G54D43*
G01X-4246Y-109426D02*
Y-189426D01*
G01D02*
X1290354D01*
G01X-4246Y-144926D02*
X1290354D01*
G01X-8246Y-93426D02*
G02I-12000J0D01*
G01X-13396D02*
G02I-6850J0D01*
G01X-20246Y-109426D02*
Y-77426D01*
G01X-4246Y-93426D02*
X-36246D01*
G01X-4246Y-109426D02*
X1290354D01*
G01X502854D02*
Y-189426D01*
G01X640354Y-109426D02*
Y-189426D01*
G01X755354Y-109426D02*
Y-189426D01*
G01X922854Y-109426D02*
Y-189426D01*
G01X1092854Y-109426D02*
Y-189426D01*
G01X1290354Y-109426D02*
Y-189426D01*
G01X1318354Y-93426D02*
G02I-12000J0D01*
G01X1313204D02*
G02I-6850J0D01*
G01X1306354Y-109426D02*
Y-77426D01*
G01X1322354Y-93426D02*
X1290354D01*
G54D34*
X475061Y23622D03*
X565612Y448818D03*
G54D25*
X38109Y363133D03*
X542500Y258171D03*
X618000Y71700D03*
X612798Y403036D03*
X617798Y403136D03*
G54D16*
X-27555Y332202D03*
Y327202D03*
Y322202D03*
Y317202D03*
Y312202D03*
Y307202D03*
Y302202D03*
Y357202D03*
Y352202D03*
Y347202D03*
Y342202D03*
Y337202D03*
G54D44*
G01X16751Y-179426D02*
Y-161926D01*
G01X25047D02*
X16751Y-172718D01*
G01X26357Y-179426D02*
X20462Y-167760D01*
G01X34032Y-179426D02*
Y-161926D01*
X44076Y-179426D01*
Y-161926D01*
G01X56554Y-179426D02*
X54807Y-179134D01*
X53279Y-177968D01*
X51969Y-176218D01*
X51095Y-174176D01*
X50659Y-171843D01*
Y-169509D01*
X51095Y-167176D01*
X51969Y-165134D01*
X53279Y-163385D01*
X54807Y-162218D01*
X56554Y-161926D01*
X58300Y-162218D01*
X59829Y-163385D01*
X61139Y-165134D01*
X62013Y-167176D01*
X62449Y-169509D01*
Y-171843D01*
X62013Y-174176D01*
X61139Y-176218D01*
X59829Y-177968D01*
X58300Y-179134D01*
X56554Y-179426D01*
G01X69469D02*
X78639Y-161926D01*
G01X69469D02*
X78639Y-179426D01*
G01X104687D02*
Y-161926D01*
X109927D01*
X111674Y-162801D01*
X112984Y-164843D01*
X113421Y-167176D01*
X112984Y-169509D01*
X111892Y-171259D01*
X109927Y-172135D01*
X104687D01*
G01X126554Y-179426D02*
X124807Y-179134D01*
X123279Y-177968D01*
X121969Y-176218D01*
X121095Y-174176D01*
X120659Y-171843D01*
Y-169509D01*
X121095Y-167176D01*
X121969Y-165134D01*
X123279Y-163385D01*
X124807Y-162218D01*
X126554Y-161926D01*
X128300Y-162218D01*
X129829Y-163385D01*
X131139Y-165134D01*
X132013Y-167176D01*
X132449Y-169509D01*
Y-171843D01*
X132013Y-174176D01*
X131139Y-176218D01*
X129829Y-177968D01*
X128300Y-179134D01*
X126554Y-179426D01*
G01X137504Y-161926D02*
X140560Y-179426D01*
X144054Y-161926D01*
X147547Y-179426D01*
X150604Y-161926D01*
G01X165921Y-179426D02*
X157187D01*
Y-161926D01*
X165921D01*
G01X162427Y-170384D02*
X157187D01*
G01X174687Y-179426D02*
Y-161926D01*
X180146D01*
X181892Y-162801D01*
X182984Y-163968D01*
X183421Y-166301D01*
X182984Y-168635D01*
X181674Y-170093D01*
X180146Y-170968D01*
X174687D01*
G01X180146D02*
X183421Y-179426D01*
G01X214054Y-161926D02*
Y-179426D01*
G01X209032Y-161926D02*
X219076D01*
G01X227187Y-179426D02*
Y-161926D01*
X232646D01*
X234392Y-162801D01*
X235484Y-163968D01*
X235921Y-166301D01*
X235484Y-168635D01*
X234174Y-170093D01*
X232646Y-170968D01*
X227187D01*
G01X232646D02*
X235921Y-179426D01*
G01X243595D02*
X249054Y-161926D01*
X254513Y-179426D01*
G01X252547Y-173301D02*
X245560D01*
G01X261532Y-179426D02*
Y-161926D01*
X271576Y-179426D01*
Y-161926D01*
G01X279469Y-177093D02*
X281216Y-178551D01*
X283181Y-179426D01*
X284927D01*
X286674Y-178551D01*
X287984Y-177093D01*
X288639Y-175051D01*
X288202Y-173010D01*
X287111Y-171259D01*
X285146Y-170093D01*
X282526Y-169509D01*
X280997Y-168343D01*
X280342Y-166301D01*
X280779Y-164259D01*
X281871Y-162801D01*
X283399Y-161926D01*
X284927D01*
X286456Y-162509D01*
X287766Y-163968D01*
G01X298934Y-161926D02*
X304174D01*
G01X301554D02*
Y-179426D01*
G01X298934D02*
X304174D01*
G01X319054Y-161926D02*
Y-179426D01*
G01X314032Y-161926D02*
X324076D01*
G01X333934D02*
X339174D01*
G01X336554D02*
Y-179426D01*
G01X333934D02*
X339174D01*
G01X354054D02*
X352307Y-179134D01*
X350779Y-177968D01*
X349469Y-176218D01*
X348595Y-174176D01*
X348159Y-171843D01*
Y-169509D01*
X348595Y-167176D01*
X349469Y-165134D01*
X350779Y-163385D01*
X352307Y-162218D01*
X354054Y-161926D01*
X355800Y-162218D01*
X357329Y-163385D01*
X358639Y-165134D01*
X359513Y-167176D01*
X359949Y-169509D01*
Y-171843D01*
X359513Y-174176D01*
X358639Y-176218D01*
X357329Y-177968D01*
X355800Y-179134D01*
X354054Y-179426D01*
G01X366532D02*
Y-161926D01*
X376576Y-179426D01*
Y-161926D01*
G01X408300Y-170093D02*
X409174Y-169218D01*
X409829Y-167760D01*
X410266Y-165717D01*
X409829Y-163968D01*
X408956Y-162801D01*
X407427Y-161926D01*
X401532D01*
Y-179426D01*
X408737D01*
X410266Y-178260D01*
X411139Y-176509D01*
X411576Y-174468D01*
X411139Y-172426D01*
X409829Y-170676D01*
X408300Y-170093D01*
X401532D01*
G01X424054Y-179426D02*
X422307Y-179134D01*
X420779Y-177968D01*
X419469Y-176218D01*
X418595Y-174176D01*
X418159Y-171843D01*
Y-169509D01*
X418595Y-167176D01*
X419469Y-165134D01*
X420779Y-163385D01*
X422307Y-162218D01*
X424054Y-161926D01*
X425800Y-162218D01*
X427329Y-163385D01*
X428639Y-165134D01*
X429513Y-167176D01*
X429949Y-169509D01*
Y-171843D01*
X429513Y-174176D01*
X428639Y-176218D01*
X427329Y-177968D01*
X425800Y-179134D01*
X424054Y-179426D01*
G01X436095D02*
X441554Y-161926D01*
X447013Y-179426D01*
G01X445047Y-173301D02*
X438060D01*
G01X454687Y-179426D02*
Y-161926D01*
X460146D01*
X461892Y-162801D01*
X462984Y-163968D01*
X463421Y-166301D01*
X462984Y-168635D01*
X461674Y-170093D01*
X460146Y-170968D01*
X454687D01*
G01X460146D02*
X463421Y-179426D01*
G01X471751D02*
Y-161926D01*
X476117D01*
X477864Y-162801D01*
X479174Y-163968D01*
X480266Y-165717D01*
X481139Y-167760D01*
X481357Y-170676D01*
X481139Y-173593D01*
X480266Y-175635D01*
X479174Y-177385D01*
X477864Y-178551D01*
X476117Y-179426D01*
X471751D01*
G01X208377Y-134426D02*
Y-116926D01*
X214054Y-131509D01*
X219731Y-116926D01*
Y-134426D01*
G01X231554D02*
X230244Y-134134D01*
X228934Y-132968D01*
X228060Y-130926D01*
X227624Y-128593D01*
X228060Y-126259D01*
X228934Y-124218D01*
X230244Y-123051D01*
X231554Y-122760D01*
X232864Y-123051D01*
X234174Y-124218D01*
X235047Y-126259D01*
X235266Y-128593D01*
X235047Y-130926D01*
X234174Y-132968D01*
X232864Y-134134D01*
X231554Y-134426D01*
G01X252984Y-116926D02*
Y-134426D01*
G01Y-131802D02*
X252111Y-133260D01*
X250800Y-134134D01*
X249272Y-134426D01*
X247526Y-133843D01*
X246216Y-132385D01*
X245342Y-130635D01*
X245124Y-128593D01*
X245342Y-126551D01*
X246216Y-124801D01*
X247526Y-123343D01*
X249272Y-122760D01*
X250800Y-123051D01*
X251892Y-123635D01*
X252984Y-124801D01*
G01X263279Y-126551D02*
X270266D01*
X269611Y-124509D01*
X268519Y-123343D01*
X266991Y-122760D01*
X265462Y-123051D01*
X264152Y-123926D01*
X263279Y-125968D01*
X262842Y-127718D01*
Y-129468D01*
X263279Y-131218D01*
X264371Y-132968D01*
X265681Y-134134D01*
X267209Y-134426D01*
X268737Y-133843D01*
X270266Y-132093D01*
G01X284054Y-134426D02*
Y-116926D01*
G01X536554Y-179426D02*
Y-161926D01*
X533934Y-165426D01*
G01Y-179426D02*
X539174D01*
G01X549906Y-164843D02*
X551216Y-163093D01*
X552744Y-162218D01*
X554491Y-161926D01*
X556674Y-162509D01*
X558202Y-163968D01*
X558639Y-165717D01*
X558421Y-167468D01*
X557547Y-168926D01*
X553181Y-171843D01*
X551216Y-173884D01*
X549906Y-176802D01*
X549469Y-179426D01*
X558639D01*
G01X566751Y-176802D02*
X568060Y-178260D01*
X569589Y-179134D01*
X571554Y-179426D01*
X573519Y-178843D01*
X575047Y-177676D01*
X576139Y-175635D01*
X576357Y-173301D01*
X575921Y-170968D01*
X574829Y-169509D01*
X573300Y-168343D01*
X571772Y-168051D01*
X570244Y-168343D01*
X568279Y-169509D01*
X568934Y-161926D01*
X574829D01*
G01X584906Y-164843D02*
X586216Y-163093D01*
X587744Y-162218D01*
X589491Y-161926D01*
X591674Y-162509D01*
X593202Y-163968D01*
X593639Y-165717D01*
X593421Y-167468D01*
X592547Y-168926D01*
X588181Y-171843D01*
X586216Y-173884D01*
X584906Y-176802D01*
X584469Y-179426D01*
X593639D01*
G01X601751Y-175926D02*
X603060Y-177968D01*
X604807Y-179134D01*
X606772Y-179426D01*
X608519Y-179134D01*
X610266Y-177676D01*
X611357Y-175926D01*
X611576Y-174176D01*
X611139Y-172135D01*
X609611Y-170676D01*
X608082Y-170093D01*
X606117D01*
G01X608082D02*
X609392Y-169218D01*
X610484Y-167760D01*
X610921Y-166010D01*
X610484Y-164259D01*
X609392Y-162801D01*
X607427Y-161926D01*
X605462Y-162218D01*
X603497Y-163385D01*
G01X523437Y-134426D02*
Y-116926D01*
X528677D01*
X530424Y-117801D01*
X531734Y-119843D01*
X532171Y-122176D01*
X531734Y-124509D01*
X530642Y-126259D01*
X528677Y-127135D01*
X523437D01*
G01X550107Y-118385D02*
X548797Y-117509D01*
X547269Y-116926D01*
X545522D01*
X543557Y-117801D01*
X542029Y-119259D01*
X540937Y-121010D01*
X540064Y-123926D01*
X539845Y-126551D01*
X540282Y-129176D01*
X540937Y-130926D01*
X542247Y-132676D01*
X543776Y-133843D01*
X545304Y-134426D01*
X546832D01*
X548361Y-133843D01*
X549671Y-132968D01*
X550763Y-131802D01*
G01X564550Y-125093D02*
X565424Y-124218D01*
X566079Y-122760D01*
X566516Y-120717D01*
X566079Y-118968D01*
X565206Y-117801D01*
X563677Y-116926D01*
X557782D01*
Y-134426D01*
X564987D01*
X566516Y-133260D01*
X567389Y-131509D01*
X567826Y-129468D01*
X567389Y-127426D01*
X566079Y-125676D01*
X564550Y-125093D01*
X557782D01*
G01X573754Y-140259D02*
X586854D01*
G01X592782Y-134426D02*
Y-116926D01*
X602826Y-134426D01*
Y-116926D01*
G01X615304Y-134426D02*
X613557Y-134134D01*
X612029Y-132968D01*
X610719Y-131218D01*
X609845Y-129176D01*
X609409Y-126843D01*
Y-124509D01*
X609845Y-122176D01*
X610719Y-120134D01*
X612029Y-118385D01*
X613557Y-117218D01*
X615304Y-116926D01*
X617050Y-117218D01*
X618579Y-118385D01*
X619889Y-120134D01*
X620763Y-122176D01*
X621199Y-124509D01*
Y-126843D01*
X620763Y-129176D01*
X619889Y-131218D01*
X618579Y-132968D01*
X617050Y-134134D01*
X615304Y-134426D01*
G01X697854Y-179426D02*
Y-161926D01*
X695234Y-165426D01*
G01Y-179426D02*
X700474D01*
G01X666145Y-116926D02*
X671604Y-134426D01*
X677063Y-116926D01*
G01X693471Y-134426D02*
X684737D01*
Y-116926D01*
X693471D01*
G01X689977Y-125384D02*
X684737D01*
G01X702237Y-134426D02*
Y-116926D01*
X707696D01*
X709442Y-117801D01*
X710534Y-118968D01*
X710971Y-121301D01*
X710534Y-123635D01*
X709224Y-125093D01*
X707696Y-125968D01*
X702237D01*
G01X707696D02*
X710971Y-134426D01*
G01X724104Y-135009D02*
X723667Y-134718D01*
Y-134134D01*
X724104Y-133843D01*
X724541Y-134134D01*
Y-134718D01*
X724104Y-135009D01*
G01X804054Y-161926D02*
Y-179426D01*
G01X799032Y-161926D02*
X809076D01*
G01X815877Y-179426D02*
Y-161926D01*
X821554Y-176509D01*
X827231Y-161926D01*
Y-179426D01*
G01X833595D02*
X839054Y-161926D01*
X844513Y-179426D01*
G01X842547Y-173301D02*
X835560D01*
G01X851969Y-177093D02*
X853716Y-178551D01*
X855681Y-179426D01*
X857427D01*
X859174Y-178551D01*
X860484Y-177093D01*
X861139Y-175051D01*
X860702Y-173010D01*
X859611Y-171259D01*
X857646Y-170093D01*
X855026Y-169509D01*
X853497Y-168343D01*
X852842Y-166301D01*
X853279Y-164259D01*
X854371Y-162801D01*
X855899Y-161926D01*
X857427D01*
X858956Y-162509D01*
X860266Y-163968D01*
G01X869251Y-179426D02*
Y-161926D01*
G01X877547D02*
X869251Y-172718D01*
G01X878857Y-179426D02*
X872962Y-167760D01*
G01X790937Y-116926D02*
Y-134426D01*
X799671D01*
G01X816734D02*
Y-122760D01*
G01Y-124801D02*
X815861Y-123635D01*
X814550Y-123051D01*
X813022Y-122760D01*
X811494Y-123343D01*
X810184Y-124509D01*
X809310Y-126259D01*
X808874Y-128593D01*
X809310Y-130926D01*
X810184Y-132676D01*
X811494Y-133843D01*
X813022Y-134426D01*
X814550Y-134134D01*
X815861Y-133260D01*
X816734Y-132093D01*
G01X825719Y-139676D02*
X827029Y-140259D01*
X828776Y-139676D01*
X829867Y-138510D01*
X830741Y-137051D01*
X832050Y-132385D01*
X834889Y-122760D01*
G01X827902D02*
X832050Y-132385D01*
G01X844529Y-126551D02*
X851516D01*
X850861Y-124509D01*
X849769Y-123343D01*
X848241Y-122760D01*
X846712Y-123051D01*
X845402Y-123926D01*
X844529Y-125968D01*
X844092Y-127718D01*
Y-129468D01*
X844529Y-131218D01*
X845621Y-132968D01*
X846931Y-134134D01*
X848459Y-134426D01*
X849987Y-133843D01*
X851516Y-132093D01*
G01X862247Y-134426D02*
Y-122760D01*
G01Y-125093D02*
X863339Y-123926D01*
X864431Y-123051D01*
X865959Y-122760D01*
X867050Y-123051D01*
X868361Y-123926D01*
G01X879529Y-132385D02*
X880621Y-133551D01*
X882149Y-134426D01*
X883459D01*
X884769Y-133843D01*
X885642Y-132968D01*
X886079Y-131802D01*
X885861Y-130051D01*
X884987Y-129176D01*
X881057Y-127426D01*
X880184Y-125384D01*
X880621Y-123926D01*
X881494Y-123051D01*
X882804Y-122760D01*
X884114Y-123051D01*
X885424Y-123926D01*
G01X924737Y-175926D02*
X925829Y-177676D01*
X927139Y-178843D01*
X928667Y-179426D01*
X930414Y-178843D01*
X931724Y-177676D01*
X933034Y-175926D01*
X933471Y-173593D01*
Y-161926D01*
G01X946604Y-179426D02*
X944857Y-179134D01*
X943329Y-177968D01*
X942019Y-176218D01*
X941145Y-174176D01*
X940709Y-171843D01*
Y-169509D01*
X941145Y-167176D01*
X942019Y-165134D01*
X943329Y-163385D01*
X944857Y-162218D01*
X946604Y-161926D01*
X948350Y-162218D01*
X949879Y-163385D01*
X951189Y-165134D01*
X952063Y-167176D01*
X952499Y-169509D01*
Y-171843D01*
X952063Y-174176D01*
X951189Y-176218D01*
X949879Y-177968D01*
X948350Y-179134D01*
X946604Y-179426D01*
G01X959519Y-177093D02*
X961266Y-178551D01*
X963231Y-179426D01*
X964977D01*
X966724Y-178551D01*
X968034Y-177093D01*
X968689Y-175051D01*
X968252Y-173010D01*
X967161Y-171259D01*
X965196Y-170093D01*
X962576Y-169509D01*
X961047Y-168343D01*
X960392Y-166301D01*
X960829Y-164259D01*
X961921Y-162801D01*
X963449Y-161926D01*
X964977D01*
X966506Y-162509D01*
X967816Y-163968D01*
G01X985971Y-179426D02*
X977237D01*
Y-161926D01*
X985971D01*
G01X982477Y-170384D02*
X977237D01*
G01X994737Y-179426D02*
Y-161926D01*
X999977D01*
X1001724Y-162801D01*
X1003034Y-164843D01*
X1003471Y-167176D01*
X1003034Y-169509D01*
X1001942Y-171259D01*
X999977Y-172135D01*
X994737D01*
G01X1012019Y-179426D02*
Y-161926D01*
G01X1021189D02*
Y-179426D01*
G01Y-170676D02*
X1012019D01*
G01X1047237Y-161926D02*
Y-179426D01*
X1055971D01*
G01X1063645D02*
X1069104Y-161926D01*
X1074563Y-179426D01*
G01X1072597Y-173301D02*
X1065610D01*
G01X1081801Y-161926D02*
Y-174468D01*
X1082674Y-177093D01*
X1084421Y-178843D01*
X1086604Y-179426D01*
X1088787Y-178843D01*
X1090534Y-177093D01*
X1091407Y-174468D01*
Y-161926D01*
G01X941801Y-134426D02*
Y-116926D01*
X946167D01*
X947914Y-117801D01*
X949224Y-118968D01*
X950316Y-120717D01*
X951189Y-122760D01*
X951407Y-125676D01*
X951189Y-128593D01*
X950316Y-130635D01*
X949224Y-132385D01*
X947914Y-133551D01*
X946167Y-134426D01*
X941801D01*
G01X960829Y-126551D02*
X967816D01*
X967161Y-124509D01*
X966069Y-123343D01*
X964541Y-122760D01*
X963012Y-123051D01*
X961702Y-123926D01*
X960829Y-125968D01*
X960392Y-127718D01*
Y-129468D01*
X960829Y-131218D01*
X961921Y-132968D01*
X963231Y-134134D01*
X964759Y-134426D01*
X966287Y-133843D01*
X967816Y-132093D01*
G01X978329Y-132385D02*
X979421Y-133551D01*
X980949Y-134426D01*
X982259D01*
X983569Y-133843D01*
X984442Y-132968D01*
X984879Y-131802D01*
X984661Y-130051D01*
X983787Y-129176D01*
X979857Y-127426D01*
X978984Y-125384D01*
X979421Y-123926D01*
X980294Y-123051D01*
X981604Y-122760D01*
X982914Y-123051D01*
X984224Y-123926D01*
G01X999104Y-122760D02*
Y-134426D01*
G01Y-118093D02*
X998667Y-117801D01*
Y-117218D01*
X999104Y-116926D01*
X999541Y-117218D01*
Y-117801D01*
X999104Y-118093D01*
G01X1013547Y-138801D02*
X1015076Y-139968D01*
X1016822Y-140259D01*
X1018350Y-139968D01*
X1019661Y-138510D01*
X1020534Y-136468D01*
Y-122760D01*
G01Y-125093D02*
X1019661Y-123926D01*
X1018350Y-123051D01*
X1016822Y-122760D01*
X1015076Y-123343D01*
X1013984Y-124509D01*
X1013110Y-126551D01*
X1012674Y-128593D01*
X1012892Y-130343D01*
X1013766Y-132385D01*
X1015076Y-133843D01*
X1016822Y-134426D01*
X1018132Y-134134D01*
X1019661Y-132968D01*
X1020534Y-131802D01*
G01X1030392Y-134426D02*
Y-122760D01*
G01Y-125676D02*
X1031266Y-124218D01*
X1032576Y-123051D01*
X1034322Y-122760D01*
X1035850Y-123051D01*
X1037161Y-124218D01*
X1037816Y-126259D01*
Y-134426D01*
G01X1048329Y-126551D02*
X1055316D01*
X1054661Y-124509D01*
X1053569Y-123343D01*
X1052041Y-122760D01*
X1050512Y-123051D01*
X1049202Y-123926D01*
X1048329Y-125968D01*
X1047892Y-127718D01*
Y-129468D01*
X1048329Y-131218D01*
X1049421Y-132968D01*
X1050731Y-134134D01*
X1052259Y-134426D01*
X1053787Y-133843D01*
X1055316Y-132093D01*
G01X1066047Y-134426D02*
Y-122760D01*
G01Y-125093D02*
X1067139Y-123926D01*
X1068231Y-123051D01*
X1069759Y-122760D01*
X1070850Y-123051D01*
X1072161Y-123926D01*
G01X1112804Y-179426D02*
Y-161926D01*
X1110184Y-165426D01*
G01Y-179426D02*
X1115424D01*
G01X1130304Y-161926D02*
X1128557Y-162509D01*
X1127247Y-163968D01*
X1126374Y-165717D01*
X1125719Y-168051D01*
X1125501Y-170676D01*
X1125719Y-173301D01*
X1126374Y-175635D01*
X1127247Y-177385D01*
X1128557Y-178843D01*
X1130304Y-179426D01*
X1132050Y-178843D01*
X1133361Y-177385D01*
X1134234Y-175635D01*
X1134889Y-173301D01*
X1135107Y-170676D01*
X1134889Y-168051D01*
X1134234Y-165717D01*
X1133361Y-163968D01*
X1132050Y-162509D01*
X1130304Y-161926D01*
G01X1143874Y-180009D02*
X1151734Y-161926D01*
G01X1165304Y-179426D02*
Y-161926D01*
X1162684Y-165426D01*
G01Y-179426D02*
X1167924D01*
G01X1179092Y-177385D02*
X1180621Y-178843D01*
X1182367Y-179426D01*
X1184114Y-178843D01*
X1185642Y-177093D01*
X1186734Y-174468D01*
X1187171Y-171843D01*
Y-168635D01*
X1186734Y-166010D01*
X1185642Y-163676D01*
X1184332Y-162509D01*
X1182804Y-161926D01*
X1181057Y-162509D01*
X1179747Y-163676D01*
X1178874Y-165426D01*
X1178437Y-167760D01*
X1178874Y-169801D01*
X1179966Y-171843D01*
X1181276Y-173010D01*
X1182804Y-173301D01*
X1184550Y-172718D01*
X1185861Y-171259D01*
X1187171Y-168635D01*
G01X1196374Y-180009D02*
X1204234Y-161926D01*
G01X1213656Y-164843D02*
X1214966Y-163093D01*
X1216494Y-162218D01*
X1218241Y-161926D01*
X1220424Y-162509D01*
X1221952Y-163968D01*
X1222389Y-165717D01*
X1222171Y-167468D01*
X1221297Y-168926D01*
X1216931Y-171843D01*
X1214966Y-173884D01*
X1213656Y-176802D01*
X1213219Y-179426D01*
X1222389D01*
G01X1235304Y-161926D02*
X1233557Y-162509D01*
X1232247Y-163968D01*
X1231374Y-165717D01*
X1230719Y-168051D01*
X1230501Y-170676D01*
X1230719Y-173301D01*
X1231374Y-175635D01*
X1232247Y-177385D01*
X1233557Y-178843D01*
X1235304Y-179426D01*
X1237050Y-178843D01*
X1238361Y-177385D01*
X1239234Y-175635D01*
X1239889Y-173301D01*
X1240107Y-170676D01*
X1239889Y-168051D01*
X1239234Y-165717D01*
X1238361Y-163968D01*
X1237050Y-162509D01*
X1235304Y-161926D01*
G01X1252804Y-179426D02*
Y-161926D01*
X1250184Y-165426D01*
G01Y-179426D02*
X1255424D01*
G01X1266156Y-164843D02*
X1267466Y-163093D01*
X1268994Y-162218D01*
X1270741Y-161926D01*
X1272924Y-162509D01*
X1274452Y-163968D01*
X1274889Y-165717D01*
X1274671Y-167468D01*
X1273797Y-168926D01*
X1269431Y-171843D01*
X1267466Y-173884D01*
X1266156Y-176802D01*
X1265719Y-179426D01*
X1274889D01*
G01X1160501Y-134426D02*
Y-116926D01*
X1164867D01*
X1166614Y-117801D01*
X1167924Y-118968D01*
X1169016Y-120717D01*
X1169889Y-122760D01*
X1170107Y-125676D01*
X1169889Y-128593D01*
X1169016Y-130635D01*
X1167924Y-132385D01*
X1166614Y-133551D01*
X1164867Y-134426D01*
X1160501D01*
G01X1186734D02*
Y-122760D01*
G01Y-124801D02*
X1185861Y-123635D01*
X1184550Y-123051D01*
X1183022Y-122760D01*
X1181494Y-123343D01*
X1180184Y-124509D01*
X1179310Y-126259D01*
X1178874Y-128593D01*
X1179310Y-130926D01*
X1180184Y-132676D01*
X1181494Y-133843D01*
X1183022Y-134426D01*
X1184550Y-134134D01*
X1185861Y-133260D01*
X1186734Y-132093D01*
G01X1200304Y-116926D02*
Y-134426D01*
G01X1197247Y-122760D02*
X1203361D01*
G01X1214529Y-126551D02*
X1221516D01*
X1220861Y-124509D01*
X1219769Y-123343D01*
X1218241Y-122760D01*
X1216712Y-123051D01*
X1215402Y-123926D01*
X1214529Y-125968D01*
X1214092Y-127718D01*
Y-129468D01*
X1214529Y-131218D01*
X1215621Y-132968D01*
X1216931Y-134134D01*
X1218459Y-134426D01*
X1219987Y-133843D01*
X1221516Y-132093D01*
G54D17*
X49902Y379652D03*
X52462D03*
X55022D03*
X57582D03*
Y363352D03*
X55022D03*
X52462D03*
X49902D03*
G54D26*
X38109Y368733D03*
X542500Y263771D03*
X618000Y77300D03*
X612798Y408636D03*
X617798Y408736D03*
G54D35*
X462000Y192300D03*
Y180700D03*
X448500Y192300D03*
Y180700D03*
X435000Y192300D03*
Y180700D03*
X421500Y192300D03*
Y180700D03*
G54D27*
X38128Y379932D03*
X45807Y393668D03*
X542500Y274771D03*
X634488Y77603D03*
G54D18*
X33508Y374132D03*
Y368932D03*
X38598Y337936D03*
Y333436D03*
X69550Y378236D03*
X69547Y373979D03*
X69498Y369470D03*
X537733Y263971D03*
Y268971D03*
X526200Y326000D03*
X533636Y326402D03*
X533536Y330602D03*
X533636Y322102D03*
G54D36*
X512989Y198162D03*
Y173362D03*
X487625Y198086D03*
Y173286D03*
X538135Y198177D03*
Y173377D03*
G54D19*
X30108Y374132D03*
Y368932D03*
X35198Y337936D03*
Y333436D03*
X66150Y378236D03*
X66147Y373979D03*
X66098Y369470D03*
X534333Y263971D03*
Y268971D03*
X522800Y326000D03*
X530236Y326402D03*
X530136Y330602D03*
X530236Y322102D03*
G54D28*
X41309Y387463D03*
G54D37*
X570709Y161889D03*
X580709D03*
X570709Y214409D03*
X580709D03*
X570709Y204409D03*
X580709D03*
X570709Y191889D03*
X580709D03*
X570709Y181889D03*
X580709D03*
X570709Y171889D03*
X580709D03*
X570709Y244409D03*
X580709D03*
X570709Y276929D03*
X580709D03*
X570709Y266929D03*
X580709D03*
X570709Y256929D03*
X580709D03*
X570709Y234409D03*
X580709D03*
X570709Y224409D03*
X580709D03*
X570709Y286929D03*
X580709D03*
X590709Y161889D03*
X600709D03*
X590709Y214409D03*
X600709D03*
X590709Y204409D03*
X600709D03*
X590709Y191889D03*
X600709D03*
X590709Y181889D03*
X600709D03*
X590709Y171889D03*
X600709D03*
X590709Y244409D03*
X600709D03*
X590709Y276929D03*
X600709D03*
X590709Y266929D03*
X600709D03*
X590709Y256929D03*
X600709D03*
X590709Y234409D03*
X600709D03*
X590709Y224409D03*
X600709D03*
X590709Y286929D03*
X600709D03*
G54D38*
X529011Y293257D03*
X532886Y300757D03*
X525136D03*
X529036Y308352D03*
X525161Y315852D03*
X532911D03*
G54D29*
X43038Y353675D03*
X28182Y364061D03*
Y379003D03*
X43072Y360525D03*
X43159Y382607D03*
X74803Y369471D03*
X81000Y372786D03*
X66041Y359891D03*
X66100Y383508D03*
X135063Y304219D03*
X176762Y319444D03*
X228716Y315094D03*
X196289Y302044D03*
X264680Y317269D03*
X310990Y310744D03*
X358093Y312919D03*
X401561Y306394D03*
X463259Y299869D03*
X439407Y308569D03*
X439585Y321619D03*
X548417Y269770D03*
Y262970D03*
X524888Y330228D03*
X540736Y309902D03*
X537936Y322102D03*
X529000Y353500D03*
X526270Y338185D03*
X623500Y71500D03*
X622598Y331736D03*
X624898Y400936D03*
G54D39*
X599055Y59055D03*
Y90551D03*
M02*
